# T6G (Grand Teton) — schematic netlist excerpt (pin names and nets, part order shuffled) for the footprints in the layout excerpt that follows; sources: Cadence DE-HDL packaged netlist, KiCad conversion of 04192023_DAF0TMB3IC0_F0TG_MB_C_brd_V02_OCP.brd

R2922  Q_RES  0 5% CHIP  pkg 0402LF  page 245 : A = RST_SMB_SWITCH_N ; B = PU_RST_SMB_U181_N
R4080  Q_RES  10K 1% CHIP  pkg 0402LF  page 233 : A = P3V3_AUX ; B = P3V3_PWRGD_CLKGEN

(kicad_pcb
	(version 20260206)
	(generator "pcbnew")
	(generator_version "10.0")
	(general
		(thickness 1.6)
		(legacy_teardrops no)
	)
	(paper "A4")
	(title_block
		(title "04192023_DAF0TMB3IC0_F0TG_MB_C_brd_V02_OCP.brd")
		(comment 1 "Grand Teton / footprints 3482-3483 of 8354")
	)
	(layers
		(0 "F.Cu" signal "TOP")
		(4 "In1.Cu" signal "GND")
		(6 "In2.Cu" signal "IN1")
		(8 "In3.Cu" signal "GND1")
		(10 "In4.Cu" signal "IN2")
		(12 "In5.Cu" signal "GND2")
		(14 "In6.Cu" signal "IN3")
		(16 "In7.Cu" signal "GND3")
		(18 "In8.Cu" signal "VCC")
		(20 "In9.Cu" signal "VCC1")
		(22 "In10.Cu" signal "GND4")
		(24 "In11.Cu" signal "IN4")
		(26 "In12.Cu" signal "GND5")
		(28 "In13.Cu" signal "IN5")
		(30 "In14.Cu" signal "GND6")
		(32 "In15.Cu" signal "IN6")
		(34 "In16.Cu" signal "GND7")
		(2 "B.Cu" signal "BOTTOM")
		(9 "F.Adhes" user "F.Adhesive")
		(11 "B.Adhes" user "B.Adhesive")
		(13 "F.Paste" user "Package Geometry/Pastemask Top")
		(15 "B.Paste" user "Package Geometry/Pastemask Bottom")
		(5 "F.SilkS" user "Ref Des/Silkscreen Top")
		(7 "B.SilkS" user "Ref Des/Silkscreen Bottom")
		(1 "F.Mask" user "Board Geometry/Soldermask Top")
		(3 "B.Mask" user "Board Geometry/Soldermask Bottom")
		(17 "Dwgs.User" user "User.Drawings")
		(19 "Cmts.User" user "User.Comments")
		(21 "Eco1.User" user "User.Eco1")
		(23 "Eco2.User" user "User.Eco2")
		(25 "Edge.Cuts" user "Board Geometry/Outline")
		(27 "Margin" user)
		(31 "F.CrtYd" user "Package Geometry/Place Bound Top")
		(29 "B.CrtYd" user "Package Geometry/Place Bound Bottom")
		(35 "F.Fab" user "Ref Des/Assembly Top")
		(33 "B.Fab" user "Ref Des/Assembly Bottom")
	)
	(footprint ""
		(layer "F.Cu")
		(at 14.82471 -139.25804 -90)
		(property "Reference" "R4080"
			(at 0 0 270)
			(layer "F.SilkS")
			(hide yes)
			(effects
				(font
					(size 1.27 1.27)
				)
			)
		)
		(property "Value" ""
			(at 0 0 270)
			(layer "F.Fab")
			(effects
				(font
					(size 1.27 1.27)
				)
			)
		)
		(duplicate_pad_numbers_are_jumpers no)
		(fp_line
			(start -0.7874 0.4064)
			(end -0.7874 -0.4064)
			(stroke
				(width 0.1524)
				(type default)
			)
			(layer "F.SilkS")
		)
		(fp_line
			(start 0.7874 0.4064)
			(end -0.7874 0.4064)
			(stroke
				(width 0.1524)
				(type default)
			)
			(layer "F.SilkS")
		)
		(fp_line
			(start -0.7874 -0.4064)
			(end 0.7874 -0.4064)
			(stroke
				(width 0.1524)
				(type default)
			)
			(layer "F.SilkS")
		)
		(fp_line
			(start 0.7874 -0.4064)
			(end 0.7874 0.4064)
			(stroke
				(width 0.1524)
				(type default)
			)
			(layer "F.SilkS")
		)
		(fp_line
			(start -0.67945 0.3048)
			(end -0.67945 -0.305054)
			(stroke
				(width 0.1)
				(type default)
			)
			(layer "F.Fab")
		)
		(fp_line
			(start -0.12065 0.3048)
			(end -0.67945 0.3048)
			(stroke
				(width 0.1)
				(type default)
			)
			(layer "F.Fab")
		)
		(fp_line
			(start 0.120396 0.3048)
			(end 0.120396 0.2794)
			(stroke
				(width 0.1)
				(type default)
			)
			(layer "F.Fab")
		)
		(fp_line
			(start 0.67945 0.3048)
			(end 0.120396 0.3048)
			(stroke
				(width 0.1)
				(type default)
			)
			(layer "F.Fab")
		)
		(fp_line
			(start -0.12065 0.2794)
			(end -0.12065 0.3048)
			(stroke
				(width 0.1)
				(type default)
			)
			(layer "F.Fab")
		)
		(fp_line
			(start 0.120396 0.2794)
			(end -0.12065 0.2794)
			(stroke
				(width 0.1)
				(type default)
			)
			(layer "F.Fab")
		)
		(fp_line
			(start -0.12065 -0.2794)
			(end 0.12065 -0.2794)
			(stroke
				(width 0.1)
				(type default)
			)
			(layer "F.Fab")
		)
		(fp_line
			(start 0.12065 -0.2794)
			(end 0.12065 -0.3048)
			(stroke
				(width 0.1)
				(type default)
			)
			(layer "F.Fab")
		)
		(fp_line
			(start 0.12065 -0.3048)
			(end 0.67945 -0.3048)
			(stroke
				(width 0.1)
				(type default)
			)
			(layer "F.Fab")
		)
		(fp_line
			(start 0.67945 -0.3048)
			(end 0.67945 0.3048)
			(stroke
				(width 0.1)
				(type default)
			)
			(layer "F.Fab")
		)
		(fp_line
			(start -0.67945 -0.305054)
			(end -0.12065 -0.305054)
			(stroke
				(width 0.1)
				(type default)
			)
			(layer "F.Fab")
		)
		(fp_line
			(start -0.12065 -0.305054)
			(end -0.12065 -0.2794)
			(stroke
				(width 0.1)
				(type default)
			)
			(layer "F.Fab")
		)
		(pad "1" smd circle
			(at -0.40005 0 270)
			(size 0 0)
			(layers "F.Cu" "F.Mask" "F.Paste")
			(net "P3V3_AUX")
		)
		(pad "2" smd circle
			(at 0.40005 0 270)
			(size 0 0)
			(layers "F.Cu" "F.Mask" "F.Paste")
			(net "P3V3_PWRGD_CLKGEN")
		)
	)
	(footprint ""
		(layer "F.Cu")
		(at 181.648608 -413.786574 90)
		(property "Reference" "R2922"
			(at 0 0 90)
			(layer "F.SilkS")
			(hide yes)
			(effects
				(font
					(size 1.27 1.27)
				)
			)
		)
		(property "Value" ""
			(at 0 0 90)
			(layer "F.Fab")
			(effects
				(font
					(size 1.27 1.27)
				)
			)
		)
		(duplicate_pad_numbers_are_jumpers no)
		(fp_line
			(start 0.7874 -0.4064)
			(end 0.7874 0.4064)
			(stroke
				(width 0.1524)
				(type default)
			)
			(layer "F.SilkS")
		)
		(fp_line
			(start -0.7874 -0.4064)
			(end 0.7874 -0.4064)
			(stroke
				(width 0.1524)
				(type default)
			)
			(layer "F.SilkS")
		)
		(fp_line
			(start 0.7874 0.4064)
			(end -0.7874 0.4064)
			(stroke
				(width 0.1524)
				(type default)
			)
			(layer "F.SilkS")
		)
		(fp_line
			(start -0.7874 0.4064)
			(end -0.7874 -0.4064)
			(stroke
				(width 0.1524)
				(type default)
			)
			(layer "F.SilkS")
		)
		(fp_line
			(start -0.12065 -0.305054)
			(end -0.12065 -0.2794)
			(stroke
				(width 0.1)
				(type default)
			)
			(layer "F.Fab")
		)
		(fp_line
			(start -0.67945 -0.305054)
			(end -0.12065 -0.305054)
			(stroke
				(width 0.1)
				(type default)
			)
			(layer "F.Fab")
		)
		(fp_line
			(start 0.67945 -0.3048)
			(end 0.67945 0.3048)
			(stroke
				(width 0.1)
				(type default)
			)
			(layer "F.Fab")
		)
		(fp_line
			(start 0.12065 -0.3048)
			(end 0.67945 -0.3048)
			(stroke
				(width 0.1)
				(type default)
			)
			(layer "F.Fab")
		)
		(fp_line
			(start 0.12065 -0.2794)
			(end 0.12065 -0.3048)
			(stroke
				(width 0.1)
				(type default)
			)
			(layer "F.Fab")
		)
		(fp_line
			(start -0.12065 -0.2794)
			(end 0.12065 -0.2794)
			(stroke
				(width 0.1)
				(type default)
			)
			(layer "F.Fab")
		)
		(fp_line
			(start 0.120396 0.2794)
			(end -0.12065 0.2794)
			(stroke
				(width 0.1)
				(type default)
			)
			(layer "F.Fab")
		)
		(fp_line
			(start -0.12065 0.2794)
			(end -0.12065 0.3048)
			(stroke
				(width 0.1)
				(type default)
			)
			(layer "F.Fab")
		)
		(fp_line
			(start 0.67945 0.3048)
			(end 0.120396 0.3048)
			(stroke
				(width 0.1)
				(type default)
			)
			(layer "F.Fab")
		)
		(fp_line
			(start 0.120396 0.3048)
			(end 0.120396 0.2794)
			(stroke
				(width 0.1)
				(type default)
			)
			(layer "F.Fab")
		)
		(fp_line
			(start -0.12065 0.3048)
			(end -0.67945 0.3048)
			(stroke
				(width 0.1)
				(type default)
			)
			(layer "F.Fab")
		)
		(fp_line
			(start -0.67945 0.3048)
			(end -0.67945 -0.305054)
			(stroke
				(width 0.1)
				(type default)
			)
			(layer "F.Fab")
		)
		(pad "1" smd circle
			(at -0.40005 0 90)
			(size 0 0)
			(layers "F.Cu" "F.Mask" "F.Paste")
			(net "RST_SMB_SWITCH_N")
		)
		(pad "2" smd circle
			(at 0.40005 0 90)
			(size 0 0)
			(layers "F.Cu" "F.Mask" "F.Paste")
			(net "PU_RST_SMB_U181_N")
		)
	)
)
